# T6G (Grand Teton) — schematic netlist excerpt (pin names and nets, part order shuffled) for the footprints in the layout excerpt that follows; sources: Cadence DE-HDL packaged netlist, KiCad conversion of 04192023_DAF0TMB3IC0_F0TG_MB_C_brd_V02_OCP.brd

C6079  Q_CAP  22UF 6.3V 20% X6S  pkg C0603  page 177 : A = P1V2_AUX ; B = GND
C6041  Q_CAP  0.1UF 25V 10% X7R  pkg 0402  page 177 : A = P3V3_AUX ; B = GND

(kicad_pcb
	(version 20260206)
	(generator "pcbnew")
	(generator_version "10.0")
	(general
		(thickness 1.6)
		(legacy_teardrops no)
	)
	(paper "A4")
	(title_block
		(title "04192023_DAF0TMB3IC0_F0TG_MB_C_brd_V02_OCP.brd")
		(comment 1 "Grand Teton / footprints 6523-6524 of 8354")
	)
	(layers
		(0 "F.Cu" signal "TOP")
		(4 "In1.Cu" signal "GND")
		(6 "In2.Cu" signal "IN1")
		(8 "In3.Cu" signal "GND1")
		(10 "In4.Cu" signal "IN2")
		(12 "In5.Cu" signal "GND2")
		(14 "In6.Cu" signal "IN3")
		(16 "In7.Cu" signal "GND3")
		(18 "In8.Cu" signal "VCC")
		(20 "In9.Cu" signal "VCC1")
		(22 "In10.Cu" signal "GND4")
		(24 "In11.Cu" signal "IN4")
		(26 "In12.Cu" signal "GND5")
		(28 "In13.Cu" signal "IN5")
		(30 "In14.Cu" signal "GND6")
		(32 "In15.Cu" signal "IN6")
		(34 "In16.Cu" signal "GND7")
		(2 "B.Cu" signal "BOTTOM")
		(9 "F.Adhes" user "F.Adhesive")
		(11 "B.Adhes" user "B.Adhesive")
		(13 "F.Paste" user "Package Geometry/Pastemask Top")
		(15 "B.Paste" user "Package Geometry/Pastemask Bottom")
		(5 "F.SilkS" user "Ref Des/Silkscreen Top")
		(7 "B.SilkS" user "Ref Des/Silkscreen Bottom")
		(1 "F.Mask" user "Board Geometry/Soldermask Top")
		(3 "B.Mask" user "Board Geometry/Soldermask Bottom")
		(17 "Dwgs.User" user "User.Drawings")
		(19 "Cmts.User" user "User.Comments")
		(21 "Eco1.User" user "User.Eco1")
		(23 "Eco2.User" user "User.Eco2")
		(25 "Edge.Cuts" user "Board Geometry/Outline")
		(27 "Margin" user)
		(31 "F.CrtYd" user "Package Geometry/Place Bound Top")
		(29 "B.CrtYd" user "Package Geometry/Place Bound Bottom")
		(35 "F.Fab" user "Ref Des/Assembly Top")
		(33 "B.Fab" user "Ref Des/Assembly Bottom")
	)
	(footprint ""
		(layer "B.Cu")
		(at 126.894844 -41.762172 -90)
		(property "Reference" "C6079"
			(at 0 0 90)
			(layer "B.SilkS")
			(hide yes)
			(effects
				(font
					(size 1.27 1.27)
				)
				(justify mirror)
			)
		)
		(property "Value" ""
			(at 0 0 90)
			(layer "B.Fab")
			(effects
				(font
					(size 1.27 1.27)
				)
				(justify mirror)
			)
		)
		(duplicate_pad_numbers_are_jumpers no)
		(fp_line
			(start -1.2954 0.5842)
			(end 1.2954 0.5842)
			(stroke
				(width 0.1524)
				(type default)
			)
			(layer "B.SilkS")
		)
		(fp_line
			(start 1.2954 0.5842)
			(end 1.2954 -0.5842)
			(stroke
				(width 0.1524)
				(type default)
			)
			(layer "B.SilkS")
		)
		(fp_line
			(start -1.2954 -0.5842)
			(end -1.2954 0.5842)
			(stroke
				(width 0.1524)
				(type default)
			)
			(layer "B.SilkS")
		)
		(fp_line
			(start 1.2954 -0.5842)
			(end -1.2954 -0.5842)
			(stroke
				(width 0.1524)
				(type default)
			)
			(layer "B.SilkS")
		)
		(fp_line
			(start -0.8636 0.4572)
			(end 0.8636 0.4572)
			(stroke
				(width 0.1)
				(type default)
			)
			(layer "B.Fab")
		)
		(fp_line
			(start 0.8636 0.4572)
			(end 0.8636 0.4064)
			(stroke
				(width 0.1)
				(type default)
			)
			(layer "B.Fab")
		)
		(fp_line
			(start -1.1938 0.4064)
			(end -0.8636 0.4064)
			(stroke
				(width 0.1)
				(type default)
			)
			(layer "B.Fab")
		)
		(fp_line
			(start -0.8636 0.4064)
			(end -0.8636 0.4572)
			(stroke
				(width 0.1)
				(type default)
			)
			(layer "B.Fab")
		)
		(fp_line
			(start 0.8636 0.4064)
			(end 1.1938 0.4064)
			(stroke
				(width 0.1)
				(type default)
			)
			(layer "B.Fab")
		)
		(fp_line
			(start 1.1938 0.4064)
			(end 1.1938 -0.4064)
			(stroke
				(width 0.1)
				(type default)
			)
			(layer "B.Fab")
		)
		(fp_line
			(start -1.1938 -0.4064)
			(end -1.1938 0.4064)
			(stroke
				(width 0.1)
				(type default)
			)
			(layer "B.Fab")
		)
		(fp_line
			(start -0.8636 -0.4064)
			(end -1.1938 -0.4064)
			(stroke
				(width 0.1)
				(type default)
			)
			(layer "B.Fab")
		)
		(fp_line
			(start 0.8636 -0.4064)
			(end 0.8636 -0.4572)
			(stroke
				(width 0.1)
				(type default)
			)
			(layer "B.Fab")
		)
		(fp_line
			(start 1.1938 -0.4064)
			(end 0.8636 -0.4064)
			(stroke
				(width 0.1)
				(type default)
			)
			(layer "B.Fab")
		)
		(fp_line
			(start -0.8636 -0.4572)
			(end -0.8636 -0.4064)
			(stroke
				(width 0.1)
				(type default)
			)
			(layer "B.Fab")
		)
		(fp_line
			(start 0.8636 -0.4572)
			(end -0.8636 -0.4572)
			(stroke
				(width 0.1)
				(type default)
			)
			(layer "B.Fab")
		)
		(pad "1" smd rect
			(at 0.7366 0 180)
			(size 0.7112 0.8128)
			(layers "B.Cu" "B.Mask" "B.Paste")
			(net "P1V2_AUX")
		)
		(pad "2" smd rect
			(at -0.7366 0 180)
			(size 0.7112 0.8128)
			(layers "B.Cu" "B.Mask" "B.Paste")
			(net "GND")
		)
	)
	(footprint ""
		(layer "B.Cu")
		(at 130.458972 -41.007792 90)
		(property "Reference" "C6041"
			(at 0 0 90)
			(layer "B.SilkS")
			(hide yes)
			(effects
				(font
					(size 1.27 1.27)
				)
				(justify mirror)
			)
		)
		(property "Value" ""
			(at 0 0 90)
			(layer "B.Fab")
			(effects
				(font
					(size 1.27 1.27)
				)
				(justify mirror)
			)
		)
		(duplicate_pad_numbers_are_jumpers no)
		(fp_line
			(start 0.7874 -0.4064)
			(end -0.7874 -0.4064)
			(stroke
				(width 0.1524)
				(type default)
			)
			(layer "B.SilkS")
		)
		(fp_line
			(start -0.7874 -0.4064)
			(end -0.7874 0.4064)
			(stroke
				(width 0.1524)
				(type default)
			)
			(layer "B.SilkS")
		)
		(fp_line
			(start 0.7874 0.4064)
			(end 0.7874 -0.4064)
			(stroke
				(width 0.1524)
				(type default)
			)
			(layer "B.SilkS")
		)
		(fp_line
			(start -0.7874 0.4064)
			(end 0.7874 0.4064)
			(stroke
				(width 0.1524)
				(type default)
			)
			(layer "B.SilkS")
		)
		(fp_line
			(start 0.67945 -0.305054)
			(end 0.12065 -0.305054)
			(stroke
				(width 0.1)
				(type default)
			)
			(layer "B.Fab")
		)
		(fp_line
			(start 0.12065 -0.305054)
			(end 0.12065 -0.2794)
			(stroke
				(width 0.1)
				(type default)
			)
			(layer "B.Fab")
		)
		(fp_line
			(start -0.12065 -0.3048)
			(end -0.67945 -0.3048)
			(stroke
				(width 0.1)
				(type default)
			)
			(layer "B.Fab")
		)
		(fp_line
			(start -0.67945 -0.3048)
			(end -0.67945 0.3048)
			(stroke
				(width 0.1)
				(type default)
			)
			(layer "B.Fab")
		)
		(fp_line
			(start 0.12065 -0.2794)
			(end -0.12065 -0.2794)
			(stroke
				(width 0.1)
				(type default)
			)
			(layer "B.Fab")
		)
		(fp_line
			(start -0.12065 -0.2794)
			(end -0.12065 -0.3048)
			(stroke
				(width 0.1)
				(type default)
			)
			(layer "B.Fab")
		)
		(fp_line
			(start 0.12065 0.2794)
			(end 0.12065 0.3048)
			(stroke
				(width 0.1)
				(type default)
			)
			(layer "B.Fab")
		)
		(fp_line
			(start -0.120396 0.2794)
			(end 0.12065 0.2794)
			(stroke
				(width 0.1)
				(type default)
			)
			(layer "B.Fab")
		)
		(fp_line
			(start 0.67945 0.3048)
			(end 0.67945 -0.305054)
			(stroke
				(width 0.1)
				(type default)
			)
			(layer "B.Fab")
		)
		(fp_line
			(start 0.12065 0.3048)
			(end 0.67945 0.3048)
			(stroke
				(width 0.1)
				(type default)
			)
			(layer "B.Fab")
		)
		(fp_line
			(start -0.120396 0.3048)
			(end -0.120396 0.2794)
			(stroke
				(width 0.1)
				(type default)
			)
			(layer "B.Fab")
		)
		(fp_line
			(start -0.67945 0.3048)
			(end -0.120396 0.3048)
			(stroke
				(width 0.1)
				(type default)
			)
			(layer "B.Fab")
		)
		(pad "1" smd circle
			(at 0.40005 0 270)
			(size 0 0)
			(layers "B.Cu" "B.Mask" "B.Paste")
			(net "P3V3_AUX")
		)
		(pad "2" smd circle
			(at -0.40005 0 270)
			(size 0 0)
			(layers "B.Cu" "B.Mask" "B.Paste")
			(net "GND")
		)
	)
)
